(kicad_pcb
	(version 20260206)
	(generator "pcbnew")
	(generator_version "10.0")
	(general
		(thickness 1.6)
		(legacy_teardrops no)
	)
	(paper "A4")
	(title_block
		(title "01162023_DA0F0TEBIF0_F0T_Expander_BD_F_brd_V02_OCP.brd")
		(comment 1 "Grand Teton / footprints 2749-2755 of 9728")
	)
	(layers
		(0 "F.Cu" signal "TOP")
		(4 "In1.Cu" signal "GND")
		(6 "In2.Cu" signal "VCC")
		(8 "In3.Cu" signal "VCC1")
		(10 "In4.Cu" signal "GND1")
		(12 "In5.Cu" signal "IN1")
		(14 "In6.Cu" signal "GND2")
		(16 "In7.Cu" signal "IN2")
		(18 "In8.Cu" signal "GND3")
		(20 "In9.Cu" signal "IN3")
		(22 "In10.Cu" signal "GND4")
		(24 "In11.Cu" signal "IN4")
		(26 "In12.Cu" signal "GND5")
		(28 "In13.Cu" signal "IN5")
		(30 "In14.Cu" signal "GND6")
		(32 "In15.Cu" signal "IN6")
		(34 "In16.Cu" signal "GND7")
		(2 "B.Cu" signal "BOTTOM")
		(9 "F.Adhes" user "F.Adhesive")
		(11 "B.Adhes" user "B.Adhesive")
		(13 "F.Paste" user "Package Geometry/Pastemask Top")
		(15 "B.Paste" user "Package Geometry/Pastemask Bottom")
		(5 "F.SilkS" user "Ref Des/Silkscreen Top")
		(7 "B.SilkS" user "Ref Des/Silkscreen Bottom")
		(1 "F.Mask" user "Board Geometry/Soldermask Top")
		(3 "B.Mask" user "Board Geometry/Soldermask Bottom")
		(17 "Dwgs.User" user "User.Drawings")
		(19 "Cmts.User" user "User.Comments")
		(21 "Eco1.User" user "User.Eco1")
		(23 "Eco2.User" user "User.Eco2")
		(25 "Edge.Cuts" user "Board Geometry/Outline")
		(27 "Margin" user)
		(31 "F.CrtYd" user "Package Geometry/Place Bound Top")
		(29 "B.CrtYd" user "Package Geometry/Place Bound Bottom")
		(35 "F.Fab" user "Ref Des/Assembly Top")
		(33 "B.Fab" user "Ref Des/Assembly Bottom")
	)
	(footprint ""
		(layer "F.Cu")
		(at 321.035934 -289.230816 90)
		(property "Reference" "R3983"
			(at 0 0 90)
			(layer "F.SilkS")
			(hide yes)
			(effects
				(font
					(size 1.27 1.27)
				)
			)
		)
		(property "Value" ""
			(at 0 0 90)
			(layer "F.Fab")
			(effects
				(font
					(size 1.27 1.27)
				)
			)
		)
		(duplicate_pad_numbers_are_jumpers no)
		(fp_line
			(start 0.7874 -0.4064)
			(end 0.7874 0.4064)
			(stroke
				(width 0.1524)
				(type default)
			)
			(layer "F.SilkS")
		)
		(fp_line
			(start -0.7874 -0.4064)
			(end 0.7874 -0.4064)
			(stroke
				(width 0.1524)
				(type default)
			)
			(layer "F.SilkS")
		)
		(fp_line
			(start 0.7874 0.4064)
			(end -0.7874 0.4064)
			(stroke
				(width 0.1524)
				(type default)
			)
			(layer "F.SilkS")
		)
		(fp_line
			(start -0.7874 0.4064)
			(end -0.7874 -0.4064)
			(stroke
				(width 0.1524)
				(type default)
			)
			(layer "F.SilkS")
		)
		(fp_line
			(start -0.12065 -0.305054)
			(end -0.12065 -0.2794)
			(stroke
				(width 0.1)
				(type default)
			)
			(layer "F.Fab")
		)
		(fp_line
			(start -0.67945 -0.305054)
			(end -0.12065 -0.305054)
			(stroke
				(width 0.1)
				(type default)
			)
			(layer "F.Fab")
		)
		(fp_line
			(start 0.67945 -0.3048)
			(end 0.67945 0.3048)
			(stroke
				(width 0.1)
				(type default)
			)
			(layer "F.Fab")
		)
		(fp_line
			(start 0.12065 -0.3048)
			(end 0.67945 -0.3048)
			(stroke
				(width 0.1)
				(type default)
			)
			(layer "F.Fab")
		)
		(fp_line
			(start 0.12065 -0.2794)
			(end 0.12065 -0.3048)
			(stroke
				(width 0.1)
				(type default)
			)
			(layer "F.Fab")
		)
		(fp_line
			(start -0.12065 -0.2794)
			(end 0.12065 -0.2794)
			(stroke
				(width 0.1)
				(type default)
			)
			(layer "F.Fab")
		)
		(fp_line
			(start 0.120396 0.2794)
			(end -0.12065 0.2794)
			(stroke
				(width 0.1)
				(type default)
			)
			(layer "F.Fab")
		)
		(fp_line
			(start -0.12065 0.2794)
			(end -0.12065 0.3048)
			(stroke
				(width 0.1)
				(type default)
			)
			(layer "F.Fab")
		)
		(fp_line
			(start 0.67945 0.3048)
			(end 0.120396 0.3048)
			(stroke
				(width 0.1)
				(type default)
			)
			(layer "F.Fab")
		)
		(fp_line
			(start 0.120396 0.3048)
			(end 0.120396 0.2794)
			(stroke
				(width 0.1)
				(type default)
			)
			(layer "F.Fab")
		)
		(fp_line
			(start -0.12065 0.3048)
			(end -0.67945 0.3048)
			(stroke
				(width 0.1)
				(type default)
			)
			(layer "F.Fab")
		)
		(fp_line
			(start -0.67945 0.3048)
			(end -0.67945 -0.305054)
			(stroke
				(width 0.1)
				(type default)
			)
			(layer "F.Fab")
		)
		(pad "1" smd circle
			(at -0.40005 0 90)
			(size 0 0)
			(layers "F.Cu" "F.Mask" "F.Paste")
			(net "SMB_PEX2_PCA9555_SDA")
		)
		(pad "2" smd circle
			(at 0.40005 0 90)
			(size 0 0)
			(layers "F.Cu" "F.Mask" "F.Paste")
			(net "SMB_PEX2_HOST_LS_SDA")
		)
	)
	(footprint ""
		(layer "F.Cu")
		(at 205.754732 -353.742752 -90)
		(property "Reference" "U415"
			(at 1.538478 4.90474 0)
			(unlocked yes)
			(layer "F.SilkS")
			(effects
				(font
					(size 0.7874 0.5842)
					(thickness 0.1524)
				)
				(justify left)
			)
		)
		(property "Value" ""
			(at 0 0 270)
			(layer "F.Fab")
			(effects
				(font
					(size 1.27 1.27)
				)
			)
		)
		(duplicate_pad_numbers_are_jumpers no)
		(fp_line
			(start -2.0574 1.651)
			(end -2.0574 -1.651)
			(stroke
				(width 0.1524)
				(type default)
			)
			(layer "F.SilkS")
		)
		(fp_line
			(start 2.0574 1.651)
			(end -2.0574 1.651)
			(stroke
				(width 0.1524)
				(type default)
			)
			(layer "F.SilkS")
		)
		(fp_line
			(start 0 -1.016)
			(end 0.381 -1.651)
			(stroke
				(width 0.1524)
				(type default)
			)
			(layer "F.SilkS")
		)
		(fp_line
			(start -2.0574 -1.651)
			(end -0.381 -1.651)
			(stroke
				(width 0.1524)
				(type default)
			)
			(layer "F.SilkS")
		)
		(fp_line
			(start -0.381 -1.651)
			(end 0 -1.016)
			(stroke
				(width 0.1524)
				(type default)
			)
			(layer "F.SilkS")
		)
		(fp_line
			(start 0.381 -1.651)
			(end 2.0574 -1.651)
			(stroke
				(width 0.1524)
				(type default)
			)
			(layer "F.SilkS")
		)
		(fp_line
			(start 2.0574 -1.651)
			(end 2.0574 1.651)
			(stroke
				(width 0.1524)
				(type default)
			)
			(layer "F.SilkS")
		)
		(fp_poly
			(pts
				(xy -2.71272 -0.719328) (xy -2.71272 -1.344168) (xy -2.159 -1.016)
			)
			(stroke
				(width 0)
				(type default)
			)
			(fill yes)
			(layer "F.SilkS")
		)
		(fp_line
			(start -0.899922 1.549908)
			(end -0.899922 1.199896)
			(stroke
				(width 0.1)
				(type default)
			)
			(layer "F.Fab")
		)
		(fp_line
			(start 0.899922 1.549908)
			(end -0.899922 1.549908)
			(stroke
				(width 0.1)
				(type default)
			)
			(layer "F.Fab")
		)
		(fp_line
			(start -1.599946 1.199896)
			(end -1.599946 -1.199896)
			(stroke
				(width 0.1)
				(type default)
			)
			(layer "F.Fab")
		)
		(fp_line
			(start -0.899922 1.199896)
			(end -1.599946 1.199896)
			(stroke
				(width 0.1)
				(type default)
			)
			(layer "F.Fab")
		)
		(fp_line
			(start 0.899922 1.199896)
			(end 0.899922 1.549908)
			(stroke
				(width 0.1)
				(type default)
			)
			(layer "F.Fab")
		)
		(fp_line
			(start 1.599946 1.199896)
			(end 0.899922 1.199896)
			(stroke
				(width 0.1)
				(type default)
			)
			(layer "F.Fab")
		)
		(fp_line
			(start -1.599946 -1.199896)
			(end -0.899922 -1.199896)
			(stroke
				(width 0.1)
				(type default)
			)
			(layer "F.Fab")
		)
		(fp_line
			(start -0.899922 -1.199896)
			(end -0.899922 -1.549908)
			(stroke
				(width 0.1)
				(type default)
			)
			(layer "F.Fab")
		)
		(fp_line
			(start 0.899922 -1.199896)
			(end 1.599946 -1.199896)
			(stroke
				(width 0.1)
				(type default)
			)
			(layer "F.Fab")
		)
		(fp_line
			(start 1.599946 -1.199896)
			(end 1.599946 1.199896)
			(stroke
				(width 0.1)
				(type default)
			)
			(layer "F.Fab")
		)
		(fp_line
			(start -0.899922 -1.549908)
			(end 0.899922 -1.549908)
			(stroke
				(width 0.1)
				(type default)
			)
			(layer "F.Fab")
		)
		(fp_line
			(start 0.899922 -1.549908)
			(end 0.899922 -1.199896)
			(stroke
				(width 0.1)
				(type default)
			)
			(layer "F.Fab")
		)
		(fp_poly
			(pts
				(xy -2.71272 -0.719328) (xy -2.71272 -1.344168) (xy -2.159 -1.016)
			)
			(stroke
				(width 0)
				(type default)
			)
			(fill yes)
			(layer "F.Fab")
		)
		(pad "1" smd rect
			(at -1.225042 -0.94996 180)
			(size 0.5588 1.3462)
			(layers "F.Cu" "F.Mask" "F.Paste")
			(net "Net_9086")
		)
		(pad "2" smd rect
			(at -1.225042 0 180)
			(size 0.5588 1.3462)
			(layers "F.Cu" "F.Mask" "F.Paste")
			(net "HSC_D_OC_R")
		)
		(pad "3" smd rect
			(at -1.225042 0.94996 180)
			(size 0.5588 1.3462)
			(layers "F.Cu" "F.Mask" "F.Paste")
			(net "GND")
		)
		(pad "4" smd rect
			(at 1.225042 0.94996 180)
			(size 0.5588 1.3462)
			(layers "F.Cu" "F.Mask" "F.Paste")
			(net "HSC_D_OC_BUF_N")
		)
		(pad "5" smd rect
			(at 1.225042 -0.94996 180)
			(size 0.5588 1.3462)
			(layers "F.Cu" "F.Mask" "F.Paste")
			(net "P3V3_AUX")
		)
	)
	(footprint ""
		(layer "F.Cu")
		(at 380.61773 -113.558574 -90)
		(property "Reference" "C4004"
			(at 0 0 270)
			(layer "F.SilkS")
			(hide yes)
			(effects
				(font
					(size 1.27 1.27)
				)
			)
		)
		(property "Value" ""
			(at 0 0 270)
			(layer "F.Fab")
			(effects
				(font
					(size 1.27 1.27)
				)
			)
		)
		(duplicate_pad_numbers_are_jumpers no)
		(fp_line
			(start -0.7874 0.4064)
			(end -0.7874 -0.4064)
			(stroke
				(width 0.1524)
				(type default)
			)
			(layer "F.SilkS")
		)
		(fp_line
			(start 0.7874 0.4064)
			(end -0.7874 0.4064)
			(stroke
				(width 0.1524)
				(type default)
			)
			(layer "F.SilkS")
		)
		(fp_line
			(start -0.7874 -0.4064)
			(end 0.7874 -0.4064)
			(stroke
				(width 0.1524)
				(type default)
			)
			(layer "F.SilkS")
		)
		(fp_line
			(start 0.7874 -0.4064)
			(end 0.7874 0.4064)
			(stroke
				(width 0.1524)
				(type default)
			)
			(layer "F.SilkS")
		)
		(fp_line
			(start -0.67945 0.3048)
			(end -0.67945 -0.305054)
			(stroke
				(width 0.1)
				(type default)
			)
			(layer "F.Fab")
		)
		(fp_line
			(start -0.12065 0.3048)
			(end -0.67945 0.3048)
			(stroke
				(width 0.1)
				(type default)
			)
			(layer "F.Fab")
		)
		(fp_line
			(start 0.120396 0.3048)
			(end 0.120396 0.2794)
			(stroke
				(width 0.1)
				(type default)
			)
			(layer "F.Fab")
		)
		(fp_line
			(start 0.67945 0.3048)
			(end 0.120396 0.3048)
			(stroke
				(width 0.1)
				(type default)
			)
			(layer "F.Fab")
		)
		(fp_line
			(start -0.12065 0.2794)
			(end -0.12065 0.3048)
			(stroke
				(width 0.1)
				(type default)
			)
			(layer "F.Fab")
		)
		(fp_line
			(start 0.120396 0.2794)
			(end -0.12065 0.2794)
			(stroke
				(width 0.1)
				(type default)
			)
			(layer "F.Fab")
		)
		(fp_line
			(start -0.12065 -0.2794)
			(end 0.12065 -0.2794)
			(stroke
				(width 0.1)
				(type default)
			)
			(layer "F.Fab")
		)
		(fp_line
			(start 0.12065 -0.2794)
			(end 0.12065 -0.3048)
			(stroke
				(width 0.1)
				(type default)
			)
			(layer "F.Fab")
		)
		(fp_line
			(start 0.12065 -0.3048)
			(end 0.67945 -0.3048)
			(stroke
				(width 0.1)
				(type default)
			)
			(layer "F.Fab")
		)
		(fp_line
			(start 0.67945 -0.3048)
			(end 0.67945 0.3048)
			(stroke
				(width 0.1)
				(type default)
			)
			(layer "F.Fab")
		)
		(fp_line
			(start -0.67945 -0.305054)
			(end -0.12065 -0.305054)
			(stroke
				(width 0.1)
				(type default)
			)
			(layer "F.Fab")
		)
		(fp_line
			(start -0.12065 -0.305054)
			(end -0.12065 -0.2794)
			(stroke
				(width 0.1)
				(type default)
			)
			(layer "F.Fab")
		)
		(pad "1" smd circle
			(at -0.40005 0 270)
			(size 0 0)
			(layers "F.Cu" "F.Mask" "F.Paste")
			(net "PRSNT_NIC6_R_N")
		)
		(pad "2" smd circle
			(at 0.40005 0 270)
			(size 0 0)
			(layers "F.Cu" "F.Mask" "F.Paste")
			(net "GND")
		)
	)
	(footprint ""
		(layer "F.Cu")
		(at 291.515038 -20.72513)
		(property "Reference" "H113"
			(at 1.748536 -2.613914 0)
			(unlocked yes)
			(layer "B.SilkS")
			(effects
				(font
					(size 0.7874 0.5842)
					(thickness 0.1524)
				)
				(justify left mirror)
			)
		)
		(property "Value" ""
			(at 0 0 0)
			(layer "F.Fab")
			(effects
				(font
					(size 1.27 1.27)
				)
			)
		)
		(duplicate_pad_numbers_are_jumpers no)
		(pad "1" thru_hole rect
			(at 0 0)
			(size 4.2164 5.0038)
			(drill 2.0066
				(offset 0.099822 0)
			)
			(layers "*.Cu" "*.Mask")
			(remove_unused_layers no)
			(net "Net_8550")
			(clearance -0.8509)
			(padstack
				(mode front_inner_back)
				(layer "Inner"
					(shape circle)
					(size 4.0132 4.0132)
					(clearance -0.7493)
				)
				(layer "B.Cu"
					(shape circle)
					(size 4.0132 4.0132)
					(clearance -0.7493)
				)
			)
		)
	)
	(footprint ""
		(layer "F.Cu")
		(at 130.104388 -247.36679)
		(property "Reference" "R6245"
			(at 0 0 0)
			(layer "F.SilkS")
			(hide yes)
			(effects
				(font
					(size 1.27 1.27)
				)
			)
		)
		(property "Value" ""
			(at 0 0 0)
			(layer "F.Fab")
			(effects
				(font
					(size 1.27 1.27)
				)
			)
		)
		(duplicate_pad_numbers_are_jumpers no)
		(fp_line
			(start -0.7874 -0.4064)
			(end 0.7874 -0.4064)
			(stroke
				(width 0.1524)
				(type default)
			)
			(layer "F.SilkS")
		)
		(fp_line
			(start -0.7874 0.4064)
			(end -0.7874 -0.4064)
			(stroke
				(width 0.1524)
				(type default)
			)
			(layer "F.SilkS")
		)
		(fp_line
			(start 0.7874 -0.4064)
			(end 0.7874 0.4064)
			(stroke
				(width 0.1524)
				(type default)
			)
			(layer "F.SilkS")
		)
		(fp_line
			(start 0.7874 0.4064)
			(end -0.7874 0.4064)
			(stroke
				(width 0.1524)
				(type default)
			)
			(layer "F.SilkS")
		)
		(fp_line
			(start -0.67945 -0.305054)
			(end -0.12065 -0.305054)
			(stroke
				(width 0.1)
				(type default)
			)
			(layer "F.Fab")
		)
		(fp_line
			(start -0.67945 0.3048)
			(end -0.67945 -0.305054)
			(stroke
				(width 0.1)
				(type default)
			)
			(layer "F.Fab")
		)
		(fp_line
			(start -0.12065 -0.305054)
			(end -0.12065 -0.2794)
			(stroke
				(width 0.1)
				(type default)
			)
			(layer "F.Fab")
		)
		(fp_line
			(start -0.12065 -0.2794)
			(end 0.12065 -0.2794)
			(stroke
				(width 0.1)
				(type default)
			)
			(layer "F.Fab")
		)
		(fp_line
			(start -0.12065 0.2794)
			(end -0.12065 0.3048)
			(stroke
				(width 0.1)
				(type default)
			)
			(layer "F.Fab")
		)
		(fp_line
			(start -0.12065 0.3048)
			(end -0.67945 0.3048)
			(stroke
				(width 0.1)
				(type default)
			)
			(layer "F.Fab")
		)
		(fp_line
			(start 0.120396 0.2794)
			(end -0.12065 0.2794)
			(stroke
				(width 0.1)
				(type default)
			)
			(layer "F.Fab")
		)
		(fp_line
			(start 0.120396 0.3048)
			(end 0.120396 0.2794)
			(stroke
				(width 0.1)
				(type default)
			)
			(layer "F.Fab")
		)
		(fp_line
			(start 0.12065 -0.3048)
			(end 0.67945 -0.3048)
			(stroke
				(width 0.1)
				(type default)
			)
			(layer "F.Fab")
		)
		(fp_line
			(start 0.12065 -0.2794)
			(end 0.12065 -0.3048)
			(stroke
				(width 0.1)
				(type default)
			)
			(layer "F.Fab")
		)
		(fp_line
			(start 0.67945 -0.3048)
			(end 0.67945 0.3048)
			(stroke
				(width 0.1)
				(type default)
			)
			(layer "F.Fab")
		)
		(fp_line
			(start 0.67945 0.3048)
			(end 0.120396 0.3048)
			(stroke
				(width 0.1)
				(type default)
			)
			(layer "F.Fab")
		)
		(pad "1" smd circle
			(at -0.40005 0)
			(size 0 0)
			(layers "F.Cu" "F.Mask" "F.Paste")
			(net "SMB_BIC_I2C6_MUX_VR_R_SCL")
		)
		(pad "2" smd circle
			(at 0.40005 0)
			(size 0 0)
			(layers "F.Cu" "F.Mask" "F.Paste")
			(net "SMB_HOTSWAP_SCL_R")
		)
	)
	(footprint ""
		(layer "F.Cu")
		(at 404.183596 -61.487812 180)
		(property "Reference" "R6024"
			(at 0 0 180)
			(layer "F.SilkS")
			(hide yes)
			(effects
				(font
					(size 1.27 1.27)
				)
			)
		)
		(property "Value" ""
			(at 0 0 180)
			(layer "F.Fab")
			(effects
				(font
					(size 1.27 1.27)
				)
			)
		)
		(duplicate_pad_numbers_are_jumpers no)
		(fp_line
			(start 0.7874 0.4064)
			(end -0.7874 0.4064)
			(stroke
				(width 0.1524)
				(type default)
			)
			(layer "F.SilkS")
		)
		(fp_line
			(start 0.7874 -0.4064)
			(end 0.7874 0.4064)
			(stroke
				(width 0.1524)
				(type default)
			)
			(layer "F.SilkS")
		)
		(fp_line
			(start -0.7874 0.4064)
			(end -0.7874 -0.4064)
			(stroke
				(width 0.1524)
				(type default)
			)
			(layer "F.SilkS")
		)
		(fp_line
			(start -0.7874 -0.4064)
			(end 0.7874 -0.4064)
			(stroke
				(width 0.1524)
				(type default)
			)
			(layer "F.SilkS")
		)
		(fp_line
			(start 0.67945 0.3048)
			(end 0.120396 0.3048)
			(stroke
				(width 0.1)
				(type default)
			)
			(layer "F.Fab")
		)
		(fp_line
			(start 0.67945 -0.3048)
			(end 0.67945 0.3048)
			(stroke
				(width 0.1)
				(type default)
			)
			(layer "F.Fab")
		)
		(fp_line
			(start 0.12065 -0.2794)
			(end 0.12065 -0.3048)
			(stroke
				(width 0.1)
				(type default)
			)
			(layer "F.Fab")
		)
		(fp_line
			(start 0.12065 -0.3048)
			(end 0.67945 -0.3048)
			(stroke
				(width 0.1)
				(type default)
			)
			(layer "F.Fab")
		)
		(fp_line
			(start 0.120396 0.3048)
			(end 0.120396 0.2794)
			(stroke
				(width 0.1)
				(type default)
			)
			(layer "F.Fab")
		)
		(fp_line
			(start 0.120396 0.2794)
			(end -0.12065 0.2794)
			(stroke
				(width 0.1)
				(type default)
			)
			(layer "F.Fab")
		)
		(fp_line
			(start -0.12065 0.3048)
			(end -0.67945 0.3048)
			(stroke
				(width 0.1)
				(type default)
			)
			(layer "F.Fab")
		)
		(fp_line
			(start -0.12065 0.2794)
			(end -0.12065 0.3048)
			(stroke
				(width 0.1)
				(type default)
			)
			(layer "F.Fab")
		)
		(fp_line
			(start -0.12065 -0.2794)
			(end 0.12065 -0.2794)
			(stroke
				(width 0.1)
				(type default)
			)
			(layer "F.Fab")
		)
		(fp_line
			(start -0.12065 -0.305054)
			(end -0.12065 -0.2794)
			(stroke
				(width 0.1)
				(type default)
			)
			(layer "F.Fab")
		)
		(fp_line
			(start -0.67945 0.3048)
			(end -0.67945 -0.305054)
			(stroke
				(width 0.1)
				(type default)
			)
			(layer "F.Fab")
		)
		(fp_line
			(start -0.67945 -0.305054)
			(end -0.12065 -0.305054)
			(stroke
				(width 0.1)
				(type default)
			)
			(layer "F.Fab")
		)
		(pad "1" smd circle
			(at -0.40005 0 180)
			(size 0 0)
			(layers "F.Cu" "F.Mask" "F.Paste")
			(net "PWRGD_P12V_SSD14_D")
		)
		(pad "2" smd circle
			(at 0.40005 0 180)
			(size 0 0)
			(layers "F.Cu" "F.Mask" "F.Paste")
			(net "PWRGD_P12V_SSD14_R")
		)
	)
	(footprint ""
		(layer "F.Cu")
		(at 375.500392 -256.478786)
		(property "Reference" "C3588"
			(at 0 0 0)
			(layer "F.SilkS")
			(hide yes)
			(effects
				(font
					(size 1.27 1.27)
				)
			)
		)
		(property "Value" ""
			(at 0 0 0)
			(layer "F.Fab")
			(effects
				(font
					(size 1.27 1.27)
				)
			)
		)
		(duplicate_pad_numbers_are_jumpers no)
		(fp_line
			(start -0.299974 -0.150114)
			(end 0.299974 -0.150114)
			(stroke
				(width 0.1)
				(type default)
			)
			(layer "F.Fab")
		)
		(fp_line
			(start -0.299974 0.150114)
			(end -0.299974 -0.150114)
			(stroke
				(width 0.1)
				(type default)
			)
			(layer "F.Fab")
		)
		(fp_line
			(start 0.299974 -0.150114)
			(end 0.299974 0.150114)
			(stroke
				(width 0.1)
				(type default)
			)
			(layer "F.Fab")
		)
		(fp_line
			(start 0.299974 0.150114)
			(end -0.299974 0.150114)
			(stroke
				(width 0.1)
				(type default)
			)
			(layer "F.Fab")
		)
		(pad "1" smd rect
			(at -0.2667 0)
			(size 0.3048 0.381)
			(layers "F.Cu" "F.Mask" "F.Paste")
			(net "P1V8_PLL0_PEX3")
		)
		(pad "2" smd rect
			(at 0.2667 0)
			(size 0.3048 0.381)
			(layers "F.Cu" "F.Mask" "F.Paste")
			(net "GND")
		)
	)
)
